(kicad_pcb
	(version 20260206)
	(generator "pcbnew")
	(generator_version "10.0")
	(general
		(thickness 1.6)
		(legacy_teardrops no)
	)
	(paper "A4")
	(title_block
		(title "Bryce Canyon_IOM_M2_16342-2_OCP.brd")
		(comment 1 "Bryce Canyon / footprints 199-206 of 1146")
	)
	(layers
		(0 "F.Cu" signal "TOP")
		(4 "In1.Cu" signal "L2GND")
		(6 "In2.Cu" signal "L3")
		(8 "In3.Cu" signal "L4VCC")
		(10 "In4.Cu" signal "L5VCC")
		(12 "In5.Cu" signal "L6")
		(14 "In6.Cu" signal "L7GND")
		(2 "B.Cu" signal "BOTTOM")
		(9 "F.Adhes" user "F.Adhesive")
		(11 "B.Adhes" user "B.Adhesive")
		(13 "F.Paste" user "Package Geometry/Pastemask Top")
		(15 "B.Paste" user "Package Geometry/Pastemask Bottom")
		(5 "F.SilkS" user "Ref Des/Silkscreen Top")
		(7 "B.SilkS" user "Ref Des/Silkscreen Bottom")
		(1 "F.Mask" user "Board Geometry/Soldermask Top")
		(3 "B.Mask" user "Board Geometry/Soldermask Bottom")
		(17 "Dwgs.User" user "User.Drawings")
		(19 "Cmts.User" user "User.Comments")
		(21 "Eco1.User" user "User.Eco1")
		(23 "Eco2.User" user "User.Eco2")
		(25 "Edge.Cuts" user "Board Geometry/Outline")
		(27 "Margin" user)
		(31 "F.CrtYd" user "Package Geometry/Place Bound Top")
		(29 "B.CrtYd" user "Package Geometry/Place Bound Bottom")
		(35 "F.Fab" user "Ref Des/Assembly Top")
		(33 "B.Fab" user "Ref Des/Assembly Bottom")
	)
	(footprint ""
		(layer "F.Cu")
		(at 216.069672 -53.813456 90)
		(property "Reference" "R472"
			(at 0 0 90)
			(layer "F.SilkS")
			(hide yes)
			(effects
				(font
					(size 1.27 1.27)
				)
			)
		)
		(property "Value" "100KR2F-L1-GP"
			(at 0.064008 -3.993896 90)
			(unlocked yes)
			(layer "F.Fab")
			(hide yes)
			(effects
				(font
					(size 1.016 1.016)
					(thickness 0.1524)
				)
			)
		)
		(property "Device Type" "R402H16"
			(at 0.064008 -5.517896 90)
			(unlocked yes)
			(layer "F.Fab")
			(hide yes)
			(effects
				(font
					(size 1.016 1.016)
					(thickness 0.1524)
				)
			)
		)
		(duplicate_pad_numbers_are_jumpers no)
		(fp_line
			(start 0.508 -0.9398)
			(end -0.508 -0.9398)
			(stroke
				(width 0.1524)
				(type default)
			)
			(layer "F.SilkS")
		)
		(fp_line
			(start -0.508 -0.9398)
			(end -0.508 0.9398)
			(stroke
				(width 0.1524)
				(type default)
			)
			(layer "F.SilkS")
		)
		(fp_rect
			(start -0.508 0.9398)
			(end 0.508 -0.9398)
			(stroke
				(width 0)
				(type default)
			)
			(fill no)
			(layer "F.CrtYd")
		)
		(fp_rect
			(start -0.508 0.9398)
			(end 0.508 -0.9398)
			(stroke
				(width 0)
				(type default)
			)
			(fill no)
			(layer "F.Fab")
		)
		(pad "1" smd custom
			(at 0 -0.4445 90)
			(size 0.1397 0.1397)
			(layers "F.Cu" "F.Mask" "F.Paste")
			(net "AGND_P5V")
			(options
				(clearance outline)
				(anchor circle)
			)
			(primitives
				(gr_poly
					(pts
						(arc
							(start -0.1778 -0.2794)
							(mid -0.249642 -0.249642)
							(end -0.2794 -0.1778)
						)
						(arc
							(start -0.2794 0.1778)
							(mid -0.249642 0.249642)
							(end -0.1778 0.2794)
						)
						(arc
							(start 0.1778 0.2794)
							(mid 0.249642 0.249642)
							(end 0.2794 0.1778)
						)
						(arc
							(start 0.2794 -0.1778)
							(mid 0.249642 -0.249642)
							(end 0.1778 -0.2794)
						)
					)
					(width 0)
					(fill yes)
				)
			)
		)
		(pad "2" smd custom
			(at 0 0.4445 90)
			(size 0.1397 0.1397)
			(layers "F.Cu" "F.Mask" "F.Paste")
			(net "P5V_MODE")
			(options
				(clearance outline)
				(anchor circle)
			)
			(primitives
				(gr_poly
					(pts
						(arc
							(start -0.1778 -0.2794)
							(mid -0.249642 -0.249642)
							(end -0.2794 -0.1778)
						)
						(arc
							(start -0.2794 0.1778)
							(mid -0.249642 0.249642)
							(end -0.1778 0.2794)
						)
						(arc
							(start 0.1778 0.2794)
							(mid 0.249642 0.249642)
							(end 0.2794 0.1778)
						)
						(arc
							(start 0.2794 -0.1778)
							(mid 0.249642 -0.249642)
							(end 0.1778 -0.2794)
						)
					)
					(width 0)
					(fill yes)
				)
			)
		)
	)
	(footprint ""
		(layer "F.Cu")
		(at 36.068 -130.5052 180)
		(property "Reference" "R308"
			(at 0 0 180)
			(layer "F.SilkS")
			(hide yes)
			(effects
				(font
					(size 1.27 1.27)
				)
			)
		)
		(property "Value" "4K7R2F-GP"
			(at 0.064008 -3.993896 180)
			(unlocked yes)
			(layer "F.Fab")
			(hide yes)
			(effects
				(font
					(size 1.016 1.016)
					(thickness 0.1524)
				)
			)
		)
		(property "Device Type" "R402H16"
			(at 0.064008 -5.517896 180)
			(unlocked yes)
			(layer "F.Fab")
			(hide yes)
			(effects
				(font
					(size 1.016 1.016)
					(thickness 0.1524)
				)
			)
		)
		(duplicate_pad_numbers_are_jumpers no)
		(fp_line
			(start 0.508 -0.9398)
			(end -0.508 -0.9398)
			(stroke
				(width 0.1524)
				(type default)
			)
			(layer "F.SilkS")
		)
		(fp_line
			(start -0.508 -0.9398)
			(end -0.508 0.9398)
			(stroke
				(width 0.1524)
				(type default)
			)
			(layer "F.SilkS")
		)
		(fp_rect
			(start -0.508 0.9398)
			(end 0.508 -0.9398)
			(stroke
				(width 0)
				(type default)
			)
			(fill no)
			(layer "F.CrtYd")
		)
		(fp_rect
			(start -0.508 0.9398)
			(end 0.508 -0.9398)
			(stroke
				(width 0)
				(type default)
			)
			(fill no)
			(layer "F.Fab")
		)
		(pad "1" smd custom
			(at 0 -0.4445 180)
			(size 0.1397 0.1397)
			(layers "F.Cu" "F.Mask" "F.Paste")
			(net "P3V3_STBY")
			(options
				(clearance outline)
				(anchor circle)
			)
			(primitives
				(gr_poly
					(pts
						(arc
							(start -0.1778 -0.2794)
							(mid -0.249642 -0.249642)
							(end -0.2794 -0.1778)
						)
						(arc
							(start -0.2794 0.1778)
							(mid -0.249642 0.249642)
							(end -0.1778 0.2794)
						)
						(arc
							(start 0.1778 0.2794)
							(mid 0.249642 0.249642)
							(end 0.2794 0.1778)
						)
						(arc
							(start 0.2794 -0.1778)
							(mid 0.249642 -0.249642)
							(end 0.1778 -0.2794)
						)
					)
					(width 0)
					(fill yes)
				)
			)
		)
		(pad "2" smd custom
			(at 0 0.4445 180)
			(size 0.1397 0.1397)
			(layers "F.Cu" "F.Mask" "F.Paste")
			(net "OSC_OE")
			(options
				(clearance outline)
				(anchor circle)
			)
			(primitives
				(gr_poly
					(pts
						(arc
							(start -0.1778 -0.2794)
							(mid -0.249642 -0.249642)
							(end -0.2794 -0.1778)
						)
						(arc
							(start -0.2794 0.1778)
							(mid -0.249642 0.249642)
							(end -0.1778 0.2794)
						)
						(arc
							(start 0.1778 0.2794)
							(mid 0.249642 0.249642)
							(end 0.2794 0.1778)
						)
						(arc
							(start 0.2794 -0.1778)
							(mid 0.249642 -0.249642)
							(end 0.1778 -0.2794)
						)
					)
					(width 0)
					(fill yes)
				)
			)
		)
	)
	(footprint ""
		(layer "F.Cu")
		(at 110.755684 -13.1572 -90)
		(property "Reference" "C149"
			(at 0 0 270)
			(layer "F.SilkS")
			(hide yes)
			(effects
				(font
					(size 1.27 1.27)
				)
			)
		)
		(property "Value" "SCD1U50V3KX-GP"
			(at 0 -2.8194 270)
			(unlocked yes)
			(layer "F.Fab")
			(hide yes)
			(effects
				(font
					(size 1.016 1.016)
					(thickness 0.1524)
				)
			)
		)
		(property "Device Type" "C603H36"
			(at 0 -4.3434 270)
			(unlocked yes)
			(layer "F.Fab")
			(hide yes)
			(effects
				(font
					(size 1.016 1.016)
					(thickness 0.1524)
				)
			)
		)
		(duplicate_pad_numbers_are_jumpers no)
		(fp_line
			(start 0.508 0)
			(end -0.508 0)
			(stroke
				(width 0.2032)
				(type default)
			)
			(layer "F.SilkS")
		)
		(fp_rect
			(start -0.5842 1.3335)
			(end 0.5842 -1.3335)
			(stroke
				(width 0)
				(type default)
			)
			(fill no)
			(layer "F.CrtYd")
		)
		(fp_rect
			(start -0.5842 1.3335)
			(end 0.5842 -1.3335)
			(stroke
				(width 0)
				(type default)
			)
			(fill no)
			(layer "F.Fab")
		)
		(pad "1" smd custom
			(at 0 -0.762 270)
			(size 0.2159 0.2159)
			(layers "F.Cu" "F.Mask" "F.Paste")
			(net "MB0_PSET_R")
			(options
				(clearance outline)
				(anchor circle)
			)
			(primitives
				(gr_poly
					(pts
						(arc
							(start -0.3302 -0.4318)
							(mid -0.402042 -0.402042)
							(end -0.4318 -0.3302)
						)
						(arc
							(start -0.4318 0.3302)
							(mid -0.402042 0.402042)
							(end -0.3302 0.4318)
						)
						(arc
							(start 0.3302 0.4318)
							(mid 0.402042 0.402042)
							(end 0.4318 0.3302)
						)
						(arc
							(start 0.4318 -0.3302)
							(mid 0.402042 -0.402042)
							(end 0.3302 -0.4318)
						)
					)
					(width 0)
					(fill yes)
				)
			)
		)
		(pad "2" smd custom
			(at 0 0.762 270)
			(size 0.2159 0.2159)
			(layers "F.Cu" "F.Mask" "F.Paste")
			(net "AGND_CURRENT_MON")
			(options
				(clearance outline)
				(anchor circle)
			)
			(primitives
				(gr_poly
					(pts
						(arc
							(start -0.3302 -0.4318)
							(mid -0.402042 -0.402042)
							(end -0.4318 -0.3302)
						)
						(arc
							(start -0.4318 0.3302)
							(mid -0.402042 0.402042)
							(end -0.3302 0.4318)
						)
						(arc
							(start 0.3302 0.4318)
							(mid 0.402042 0.402042)
							(end 0.4318 0.3302)
						)
						(arc
							(start 0.4318 -0.3302)
							(mid 0.402042 -0.402042)
							(end 0.3302 -0.4318)
						)
					)
					(width 0)
					(fill yes)
				)
			)
		)
	)
	(footprint ""
		(layer "F.Cu")
		(at 215.968072 -48.911256 90)
		(property "Reference" "G2"
			(at 0 0 90)
			(layer "F.SilkS")
			(hide yes)
			(effects
				(font
					(size 1.27 1.27)
				)
			)
		)
		(property "Value" "COPPER-CLOSE-GP-U"
			(at 0.0762 -2.8702 90)
			(unlocked yes)
			(layer "F.Fab")
			(hide yes)
			(effects
				(font
					(size 1.016 1.016)
					(thickness 0.1524)
				)
			)
		)
		(property "Device Type" "CON2C-U"
			(at 0.0762 -4.3942 90)
			(unlocked yes)
			(layer "F.Fab")
			(hide yes)
			(effects
				(font
					(size 1.016 1.016)
					(thickness 0.1524)
				)
			)
		)
		(duplicate_pad_numbers_are_jumpers no)
		(fp_rect
			(start -0.9398 0.9652)
			(end 0.9398 -0.9652)
			(stroke
				(width 0)
				(type default)
			)
			(fill no)
			(layer "F.CrtYd")
		)
		(fp_rect
			(start -0.9398 0.9652)
			(end 0.9398 -0.9652)
			(stroke
				(width 0)
				(type default)
			)
			(fill no)
			(layer "F.Fab")
		)
		(pad "1" smd custom
			(at 0 -0.5334 90)
			(size 0.17145 0.17145)
			(layers "F.Cu" "F.Mask" "F.Paste")
			(net "AGND_P5V")
			(options
				(clearance outline)
				(anchor circle)
			)
			(primitives
				(gr_poly
					(pts
						(xy -0.127 0.3429) (xy -0.127 0.1651) (xy -0.635 -0.3429) (xy 0.635 -0.3429) (xy 0.127 0.1651)
						(xy 0.127 0.3429)
					)
					(width 0)
					(fill yes)
				)
			)
		)
		(pad "2" smd custom
			(at 0 0.5334 90)
			(size 0.17145 0.17145)
			(layers "F.Cu" "F.Mask" "F.Paste")
			(net "GND")
			(options
				(clearance outline)
				(anchor circle)
			)
			(primitives
				(gr_poly
					(pts
						(xy -0.635 0.3429) (xy -0.127 -0.1651) (xy -0.127 -0.3429) (xy 0.127 -0.3429) (xy 0.127 -0.1651)
						(xy 0.635 0.3429)
					)
					(width 0)
					(fill yes)
				)
			)
		)
	)
	(footprint ""
		(layer "F.Cu")
		(at 87.638636 -29.238448)
		(property "Reference" "C21"
			(at 0 0 0)
			(layer "F.SilkS")
			(hide yes)
			(effects
				(font
					(size 1.27 1.27)
				)
			)
		)
		(property "Value" "SC1U16V3KX-5GP"
			(at 0 -2.8194 0)
			(unlocked yes)
			(layer "F.Fab")
			(hide yes)
			(effects
				(font
					(size 1.016 1.016)
					(thickness 0.1524)
				)
			)
		)
		(property "Device Type" "C603H36"
			(at 0 -4.3434 0)
			(unlocked yes)
			(layer "F.Fab")
			(hide yes)
			(effects
				(font
					(size 1.016 1.016)
					(thickness 0.1524)
				)
			)
		)
		(duplicate_pad_numbers_are_jumpers no)
		(fp_line
			(start 0.508 0)
			(end -0.508 0)
			(stroke
				(width 0.2032)
				(type default)
			)
			(layer "F.SilkS")
		)
		(fp_rect
			(start -0.5842 1.3335)
			(end 0.5842 -1.3335)
			(stroke
				(width 0)
				(type default)
			)
			(fill no)
			(layer "F.CrtYd")
		)
		(fp_rect
			(start -0.5842 1.3335)
			(end 0.5842 -1.3335)
			(stroke
				(width 0)
				(type default)
			)
			(fill no)
			(layer "F.Fab")
		)
		(pad "1" smd custom
			(at 0 -0.762)
			(size 0.2159 0.2159)
			(layers "F.Cu" "F.Mask" "F.Paste")
			(net "P5V_USB")
			(options
				(clearance outline)
				(anchor circle)
			)
			(primitives
				(gr_poly
					(pts
						(arc
							(start -0.3302 -0.4318)
							(mid -0.402042 -0.402042)
							(end -0.4318 -0.3302)
						)
						(arc
							(start -0.4318 0.3302)
							(mid -0.402042 0.402042)
							(end -0.3302 0.4318)
						)
						(arc
							(start 0.3302 0.4318)
							(mid 0.402042 0.402042)
							(end 0.4318 0.3302)
						)
						(arc
							(start 0.4318 -0.3302)
							(mid 0.402042 -0.402042)
							(end 0.3302 -0.4318)
						)
					)
					(width 0)
					(fill yes)
				)
			)
		)
		(pad "2" smd custom
			(at 0 0.762)
			(size 0.2159 0.2159)
			(layers "F.Cu" "F.Mask" "F.Paste")
			(net "GND")
			(options
				(clearance outline)
				(anchor circle)
			)
			(primitives
				(gr_poly
					(pts
						(arc
							(start -0.3302 -0.4318)
							(mid -0.402042 -0.402042)
							(end -0.4318 -0.3302)
						)
						(arc
							(start -0.4318 0.3302)
							(mid -0.402042 0.402042)
							(end -0.3302 0.4318)
						)
						(arc
							(start 0.3302 0.4318)
							(mid 0.402042 0.402042)
							(end 0.4318 0.3302)
						)
						(arc
							(start 0.4318 -0.3302)
							(mid 0.402042 -0.402042)
							(end 0.3302 -0.4318)
						)
					)
					(width 0)
					(fill yes)
				)
			)
		)
	)
	(footprint ""
		(layer "F.Cu")
		(at 224.185988 -37.290756)
		(property "Reference" "L7"
			(at 0 0 0)
			(layer "F.SilkS")
			(hide yes)
			(effects
				(font
					(size 1.27 1.27)
				)
			)
		)
		(property "Value" "IND-4D7UH-291-GP"
			(at -6.34492 -3.502152 0)
			(unlocked yes)
			(layer "F.Fab")
			(hide yes)
			(effects
				(font
					(size 1.016 1.016)
					(thickness 0.1524)
				)
			)
		)
		(property "Device Type" "L11102530H158"
			(at -6.3246 -5.08 0)
			(unlocked yes)
			(layer "F.Fab")
			(hide yes)
			(effects
				(font
					(size 1.016 1.016)
					(thickness 0.1524)
				)
			)
		)
		(duplicate_pad_numbers_are_jumpers no)
		(fp_line
			(start -5.2578 -6.3754)
			(end -5.2578 6.3754)
			(stroke
				(width 0.1524)
				(type default)
			)
			(layer "F.SilkS")
		)
		(fp_line
			(start -5.2578 6.3754)
			(end 5.2578 6.3754)
			(stroke
				(width 0.1524)
				(type default)
			)
			(layer "F.SilkS")
		)
		(fp_line
			(start 5.2578 -6.3754)
			(end -5.2578 -6.3754)
			(stroke
				(width 0.1524)
				(type default)
			)
			(layer "F.SilkS")
		)
		(fp_line
			(start 5.2578 6.3754)
			(end 5.2578 -6.3754)
			(stroke
				(width 0.1524)
				(type default)
			)
			(layer "F.SilkS")
		)
		(fp_rect
			(start -5.0038 5.4991)
			(end 5.0038 -5.4991)
			(stroke
				(width 0)
				(type default)
			)
			(fill no)
			(layer "F.CrtYd")
		)
		(fp_poly
			(pts
				(xy -5.5118 6.4516) (xy -5.5118 -6.4516) (xy 5.5118 -6.4516) (xy 5.5118 -0.8509) (xy 5.0038 -0.8509)
				(xy 5.0038 -5.4991) (xy -5.0038 -5.4991) (xy -5.0038 5.4991) (xy 5.0038 5.4991) (xy 5.0038 -0.8382)
				(xy 5.5118 -0.8382) (xy 5.5118 6.4516)
			)
			(stroke
				(width 0)
				(type default)
			)
			(fill no)
			(layer "F.CrtYd")
		)
		(fp_rect
			(start -5.5118 6.4516)
			(end 5.5118 -6.4516)
			(stroke
				(width 0)
				(type default)
			)
			(fill no)
			(layer "F.Fab")
		)
		(pad "1" smd rect
			(at 0 -4.435094)
			(size 3.2512 3.3782)
			(layers "F.Cu" "F.Mask" "F.Paste")
			(net "P5V_LL")
		)
		(pad "2" smd rect
			(at 0 4.435094)
			(size 3.2512 3.3782)
			(layers "F.Cu" "F.Mask" "F.Paste")
			(net "P5V_STBY")
		)
	)
	(footprint ""
		(layer "F.Cu")
		(at 94.6658 -124.587 180)
		(property "Reference" "U46"
			(at 0 0 180)
			(layer "F.SilkS")
			(hide yes)
			(effects
				(font
					(size 1.27 1.27)
				)
			)
		)
		(property "Value" "SN74LVC1G08DCKR-GP"
			(at -2.3368 -8.6868 180)
			(unlocked yes)
			(layer "F.Fab")
			(hide yes)
			(effects
				(font
					(size 1.016 1.016)
					(thickness 0.1524)
				)
			)
		)
		(property "Device Type" "SC70-5H44"
			(at -2.3114 -10.414 180)
			(unlocked yes)
			(layer "F.Fab")
			(hide yes)
			(effects
				(font
					(size 1.016 1.016)
					(thickness 0.1524)
				)
			)
		)
		(duplicate_pad_numbers_are_jumpers no)
		(fp_line
			(start 1.3843 -1.8034)
			(end 1.3843 -1.1176)
			(stroke
				(width 0.3302)
				(type default)
			)
			(layer "F.SilkS")
		)
		(fp_line
			(start 1.27 1.7018)
			(end -1.27 1.7018)
			(stroke
				(width 0.1524)
				(type default)
			)
			(layer "F.SilkS")
		)
		(fp_line
			(start 1.27 -1.7018)
			(end 1.27 1.7018)
			(stroke
				(width 0.1524)
				(type default)
			)
			(layer "F.SilkS")
		)
		(fp_line
			(start 0.6604 -1.8034)
			(end 1.3843 -1.8034)
			(stroke
				(width 0.3302)
				(type default)
			)
			(layer "F.SilkS")
		)
		(fp_line
			(start -1.27 1.7018)
			(end -1.27 -1.7018)
			(stroke
				(width 0.1524)
				(type default)
			)
			(layer "F.SilkS")
		)
		(fp_line
			(start -1.27 -1.7018)
			(end 1.27 -1.7018)
			(stroke
				(width 0.1524)
				(type default)
			)
			(layer "F.SilkS")
		)
		(fp_rect
			(start -1.524 1.9558)
			(end 1.524 -1.9558)
			(stroke
				(width 0)
				(type default)
			)
			(fill no)
			(layer "F.CrtYd")
		)
		(fp_poly
			(pts
				(xy -1.524 -1.9558) (xy 1.524 -1.9558) (xy 1.524 1.9558) (xy -1.524 1.9558)
			)
			(stroke
				(width 0)
				(type default)
			)
			(fill no)
			(layer "F.Fab")
		)
		(pad "1" smd rect
			(at 0.65024 -0.8255 180)
			(size 0.4064 1.2192)
			(layers "F.Cu" "F.Mask" "F.Paste")
			(net "UART_COMP_IN_R_RX")
		)
		(pad "2" smd rect
			(at 0 -0.8255 180)
			(size 0.4064 1.2192)
			(layers "F.Cu" "F.Mask" "F.Paste")
			(net "UART_BMC_COMP_IN_RX_R")
		)
		(pad "3" smd rect
			(at -0.65024 -0.8255 180)
			(size 0.4064 1.2192)
			(layers "F.Cu" "F.Mask" "F.Paste")
			(net "GND")
		)
		(pad "4" smd rect
			(at -0.65024 0.8255 180)
			(size 0.4064 1.2192)
			(layers "F.Cu" "F.Mask" "F.Paste")
			(net "UART_COMP_IN_RX_AND")
		)
		(pad "5" smd rect
			(at 0.65024 0.8255 180)
			(size 0.4064 1.2192)
			(layers "F.Cu" "F.Mask" "F.Paste")
			(net "P3V3_STBY")
		)
	)
	(footprint ""
		(layer "F.Cu")
		(at 48.6156 -128.0414 180)
		(property "Reference" "R88"
			(at 0 0 180)
			(layer "F.SilkS")
			(hide yes)
			(effects
				(font
					(size 1.27 1.27)
				)
			)
		)
		(property "Value" "100KR2F-L1-GP"
			(at 0.064008 -3.993896 180)
			(unlocked yes)
			(layer "F.Fab")
			(hide yes)
			(effects
				(font
					(size 1.016 1.016)
					(thickness 0.1524)
				)
			)
		)
		(property "Device Type" "R402H16"
			(at 0.064008 -5.517896 180)
			(unlocked yes)
			(layer "F.Fab")
			(hide yes)
			(effects
				(font
					(size 1.016 1.016)
					(thickness 0.1524)
				)
			)
		)
		(duplicate_pad_numbers_are_jumpers no)
		(fp_line
			(start 0.508 -0.9398)
			(end -0.508 -0.9398)
			(stroke
				(width 0.1524)
				(type default)
			)
			(layer "F.SilkS")
		)
		(fp_line
			(start -0.508 -0.9398)
			(end -0.508 0.9398)
			(stroke
				(width 0.1524)
				(type default)
			)
			(layer "F.SilkS")
		)
		(fp_rect
			(start -0.508 0.9398)
			(end 0.508 -0.9398)
			(stroke
				(width 0)
				(type default)
			)
			(fill no)
			(layer "F.CrtYd")
		)
		(fp_rect
			(start -0.508 0.9398)
			(end 0.508 -0.9398)
			(stroke
				(width 0)
				(type default)
			)
			(fill no)
			(layer "F.Fab")
		)
		(pad "1" smd custom
			(at 0 -0.4445 180)
			(size 0.1397 0.1397)
			(layers "F.Cu" "F.Mask" "F.Paste")
			(net "SCC_LOC_FULL_PWR_EN")
			(options
				(clearance outline)
				(anchor circle)
			)
			(primitives
				(gr_poly
					(pts
						(arc
							(start -0.1778 -0.2794)
							(mid -0.249642 -0.249642)
							(end -0.2794 -0.1778)
						)
						(arc
							(start -0.2794 0.1778)
							(mid -0.249642 0.249642)
							(end -0.1778 0.2794)
						)
						(arc
							(start 0.1778 0.2794)
							(mid 0.249642 0.249642)
							(end 0.2794 0.1778)
						)
						(arc
							(start 0.2794 -0.1778)
							(mid 0.249642 -0.249642)
							(end 0.1778 -0.2794)
						)
					)
					(width 0)
					(fill yes)
				)
			)
		)
		(pad "2" smd custom
			(at 0 0.4445 180)
			(size 0.1397 0.1397)
			(layers "F.Cu" "F.Mask" "F.Paste")
			(net "GND")
			(options
				(clearance outline)
				(anchor circle)
			)
			(primitives
				(gr_poly
					(pts
						(arc
							(start -0.1778 -0.2794)
							(mid -0.249642 -0.249642)
							(end -0.2794 -0.1778)
						)
						(arc
							(start -0.2794 0.1778)
							(mid -0.249642 0.249642)
							(end -0.1778 0.2794)
						)
						(arc
							(start 0.1778 0.2794)
							(mid 0.249642 0.249642)
							(end 0.2794 0.1778)
						)
						(arc
							(start 0.2794 -0.1778)
							(mid 0.249642 -0.249642)
							(end 0.1778 -0.2794)
						)
					)
					(width 0)
					(fill yes)
				)
			)
		)
	)
)
